(kicad_pcb
	(version 20260206)
	(generator "pcbnew")
	(generator_version "10.0")
	(general
		(thickness 1.6)
		(legacy_teardrops no)
	)
	(paper "A4")
	(title_block
		(title "netronome-mezz — pcbd0082-001_rev01_jul9_a.brd")
		(comment 1 "Open CloudServer (Microsoft) / footprints 461-469 of 714")
	)
	(layers
		(0 "F.Cu" signal "TOP")
		(4 "In1.Cu" signal "02_GND")
		(6 "In2.Cu" signal "03_SIG")
		(8 "In3.Cu" signal "04_SIG")
		(10 "In4.Cu" signal "05_GND")
		(12 "In5.Cu" signal "06_PWR1")
		(14 "In6.Cu" signal "07_SIG")
		(16 "In7.Cu" signal "08_SIG")
		(18 "In8.Cu" signal "09_GND")
		(2 "B.Cu" signal "BOTTOM")
		(9 "F.Adhes" user "F.Adhesive")
		(11 "B.Adhes" user "B.Adhesive")
		(13 "F.Paste" user "Package Geometry/Pastemask Top")
		(15 "B.Paste" user "Package Geometry/Pastemask Bottom")
		(5 "F.SilkS" user "Ref Des/Silkscreen Top")
		(7 "B.SilkS" user "Ref Des/Silkscreen Bottom")
		(1 "F.Mask" user "Board Geometry/Soldermask Top")
		(3 "B.Mask" user "Board Geometry/Soldermask Bottom")
		(17 "Dwgs.User" user "User.Drawings")
		(19 "Cmts.User" user "User.Comments")
		(21 "Eco1.User" user "User.Eco1")
		(23 "Eco2.User" user "User.Eco2")
		(25 "Edge.Cuts" user "Board Geometry/Outline")
		(27 "Margin" user)
		(31 "F.CrtYd" user "Package Geometry/Place Bound Top")
		(29 "B.CrtYd" user "Package Geometry/Place Bound Bottom")
		(35 "F.Fab" user "Ref Des/Assembly Top")
		(33 "B.Fab" user "Ref Des/Assembly Bottom")
		(45 "User.4" user "COMPVAL_TYPE_BOTTOM")
	)
	(footprint ""
		(layer "B.Cu")
		(at 4.572 17.4498)
		(property "Reference" "R376"
			(at 0.98933 3.8862 270)
			(unlocked yes)
			(layer "B.SilkS")
			(effects
				(font
					(size 0.7874 0.5842)
					(thickness 0.127)
				)
				(justify left mirror)
			)
		)
		(property "Value" "4.75K"
			(at 0.148158 1.3462 270)
			(unlocked yes)
			(layer "B.Fab")
			(hide yes)
			(effects
				(font
					(size 1.27 0.9652)
					(thickness 0.000001)
				)
				(justify left mirror)
			)
		)
		(property "Device Type" "REST4024"
			(at 0.148158 1.3462 270)
			(unlocked yes)
			(layer "B.Fab")
			(hide yes)
			(effects
				(font
					(size 1.27 0.9652)
					(thickness 0.000001)
				)
				(justify left mirror)
			)
		)
		(duplicate_pad_numbers_are_jumpers no)
		(fp_poly
			(pts
				(xy -0.635 1.0668) (xy -0.635 -1.0668) (xy 0.635 -1.0668) (xy 0.635 1.0668)
			)
			(stroke
				(width 0)
				(type default)
			)
			(fill no)
			(layer "B.CrtYd")
		)
		(fp_line
			(start -0.254 -0.508)
			(end -0.254 0.508)
			(stroke
				(width 0.0254)
				(type default)
			)
			(layer "B.Fab")
		)
		(fp_line
			(start -0.254 0.508)
			(end 0.254 0.508)
			(stroke
				(width 0.0254)
				(type default)
			)
			(layer "B.Fab")
		)
		(fp_line
			(start 0.254 -0.508)
			(end -0.254 -0.508)
			(stroke
				(width 0.0254)
				(type default)
			)
			(layer "B.Fab")
		)
		(fp_line
			(start 0.254 0.508)
			(end 0.254 -0.508)
			(stroke
				(width 0.0254)
				(type default)
			)
			(layer "B.Fab")
		)
		(pad "1" smd rect
			(at 0 -0.4191 180)
			(size 0.508 0.5334)
			(layers "B.Cu" "B.Mask" "B.Paste")
			(net "13N4351")
		)
		(pad "2" smd rect
			(at 0 0.4191 180)
			(size 0.508 0.5334)
			(layers "B.Cu" "B.Mask" "B.Paste")
			(net "GND")
		)
		(zone
			(layer "B.Cu")
			(hatch none 0.5)
			(connect_pads
				(clearance 0)
			)
			(min_thickness 0.25)
			(keepout
				(tracks not_allowed)
				(vias allowed)
				(pads allowed)
				(copperpour not_allowed)
				(footprints allowed)
			)
			(placement
				(enabled no)
				(sheetname "")
			)
			(fill
				(thermal_gap 0.5)
				(thermal_bridge_width 0.5)
				(island_removal_mode 0)
			)
			(polygon
				(pts
					(xy 4.5466 17.4244) (xy 4.5466 17.4752) (xy 4.5974 17.4752) (xy 4.5974 17.4244)
				)
			)
		)
	)
	(footprint ""
		(layer "B.Cu")
		(at 43.5229 38.735 180)
		(property "Reference" "C46"
			(at 0.87757 -0.254 270)
			(unlocked yes)
			(layer "B.SilkS")
			(effects
				(font
					(size 0.7874 0.5842)
					(thickness 0.127)
				)
				(justify left mirror)
			)
		)
		(property "Value" "1000PF"
			(at 0.091846 0.2921 90)
			(unlocked yes)
			(layer "B.Fab")
			(hide yes)
			(effects
				(font
					(size 0.7874 0.5842)
					(thickness 0.2032)
				)
				(justify left mirror)
			)
		)
		(property "Device Type" "CAPC0083"
			(at 0.091846 0.2921 90)
			(unlocked yes)
			(layer "B.Fab")
			(hide yes)
			(effects
				(font
					(size 0.7874 0.5842)
					(thickness 0.2032)
				)
				(justify left mirror)
			)
		)
		(duplicate_pad_numbers_are_jumpers no)
		(fp_poly
			(pts
				(xy -0.635 1.0668) (xy -0.635 -1.0668) (xy 0.635 -1.0668) (xy 0.635 1.0668)
			)
			(stroke
				(width 0)
				(type default)
			)
			(fill no)
			(layer "B.CrtYd")
		)
		(fp_line
			(start 0.254 0.508)
			(end 0.254 -0.508)
			(stroke
				(width 0.0254)
				(type default)
			)
			(layer "B.Fab")
		)
		(fp_line
			(start 0.254 -0.508)
			(end -0.254 -0.508)
			(stroke
				(width 0.0254)
				(type default)
			)
			(layer "B.Fab")
		)
		(fp_line
			(start -0.254 0.508)
			(end 0.254 0.508)
			(stroke
				(width 0.0254)
				(type default)
			)
			(layer "B.Fab")
		)
		(fp_line
			(start -0.254 -0.508)
			(end -0.254 0.508)
			(stroke
				(width 0.0254)
				(type default)
			)
			(layer "B.Fab")
		)
		(pad "1" smd rect
			(at 0 -0.4191)
			(size 0.508 0.5334)
			(layers "B.Cu" "B.Mask" "B.Paste")
			(net "10N2223")
		)
		(pad "2" smd rect
			(at 0 0.4191)
			(size 0.508 0.5334)
			(layers "B.Cu" "B.Mask" "B.Paste")
			(net "GND")
		)
		(zone
			(layer "B.Cu")
			(hatch none 0.5)
			(connect_pads
				(clearance 0)
			)
			(min_thickness 0.25)
			(keepout
				(tracks not_allowed)
				(vias allowed)
				(pads allowed)
				(copperpour not_allowed)
				(footprints allowed)
			)
			(placement
				(enabled no)
				(sheetname "")
			)
			(fill
				(thermal_gap 0.5)
				(thermal_bridge_width 0.5)
				(island_removal_mode 0)
			)
			(polygon
				(pts
					(xy 43.5483 38.7604) (xy 43.5483 38.7096) (xy 43.4975 38.7096) (xy 43.4975 38.7604)
				)
			)
		)
	)
	(footprint ""
		(layer "B.Cu")
		(at 82.65099 6.698996)
		(property "Reference" "V1_A-A01"
			(at 0 0 0)
			(layer "B.SilkS")
			(hide yes)
			(effects
				(font
					(size 1.27 1.27)
				)
				(justify mirror)
			)
		)
		(property "Value" ""
			(at 0 0 0)
			(layer "B.Fab")
			(effects
				(font
					(size 1.27 1.27)
				)
				(justify mirror)
			)
		)
		(duplicate_pad_numbers_are_jumpers no)
		(pad "1" thru_hole circle
			(at 0 0 180)
			(size 0.4572 0.4572)
			(drill 0.20574)
			(layers "*.Cu" "*.Mask")
			(remove_unused_layers no)
			(net "DDR0_32A_A1")
			(clearance 0.1143)
			(thermal_gap 0.1143)
		)
	)
	(footprint ""
		(layer "B.Cu")
		(at 81.050994 13.456006)
		(property "Reference" "V2_A-BA0"
			(at 0 0 0)
			(layer "B.SilkS")
			(hide yes)
			(effects
				(font
					(size 1.27 1.27)
				)
				(justify mirror)
			)
		)
		(property "Value" ""
			(at 0 0 0)
			(layer "B.Fab")
			(effects
				(font
					(size 1.27 1.27)
				)
				(justify mirror)
			)
		)
		(duplicate_pad_numbers_are_jumpers no)
		(pad "1" thru_hole circle
			(at 0 0 180)
			(size 0.4572 0.4572)
			(drill 0.20574)
			(layers "*.Cu" "*.Mask")
			(remove_unused_layers no)
			(net "DDR0_32A_BA0")
			(clearance 0.1143)
			(thermal_gap 0.1143)
		)
	)
	(footprint ""
		(layer "B.Cu")
		(at 47.0789 35.7124 180)
		(property "Reference" "C204"
			(at 0 0 0)
			(layer "B.SilkS")
			(hide yes)
			(effects
				(font
					(size 1.27 1.27)
				)
				(justify mirror)
			)
		)
		(property "Value" "1UF"
			(at 0.091846 0.2921 90)
			(unlocked yes)
			(layer "B.Fab")
			(hide yes)
			(effects
				(font
					(size 0.7874 0.5842)
					(thickness 0.2032)
				)
				(justify left mirror)
			)
		)
		(property "Device Type" "CAPC0028"
			(at 0.091846 0.2921 90)
			(unlocked yes)
			(layer "B.Fab")
			(hide yes)
			(effects
				(font
					(size 0.7874 0.5842)
					(thickness 0.2032)
				)
				(justify left mirror)
			)
		)
		(duplicate_pad_numbers_are_jumpers no)
		(fp_poly
			(pts
				(xy -0.635 1.0668) (xy -0.635 -1.0668) (xy 0.635 -1.0668) (xy 0.635 1.0668)
			)
			(stroke
				(width 0)
				(type default)
			)
			(fill no)
			(layer "B.CrtYd")
		)
		(fp_line
			(start 0.254 0.508)
			(end 0.254 -0.508)
			(stroke
				(width 0.0254)
				(type default)
			)
			(layer "B.Fab")
		)
		(fp_line
			(start 0.254 -0.508)
			(end -0.254 -0.508)
			(stroke
				(width 0.0254)
				(type default)
			)
			(layer "B.Fab")
		)
		(fp_line
			(start -0.254 0.508)
			(end 0.254 0.508)
			(stroke
				(width 0.0254)
				(type default)
			)
			(layer "B.Fab")
		)
		(fp_line
			(start -0.254 -0.508)
			(end -0.254 0.508)
			(stroke
				(width 0.0254)
				(type default)
			)
			(layer "B.Fab")
		)
		(pad "1" smd rect
			(at 0 -0.4191)
			(size 0.508 0.5334)
			(layers "B.Cu" "B.Mask" "B.Paste")
			(net "VDD_5.0V")
		)
		(pad "2" smd rect
			(at 0 0.4191)
			(size 0.508 0.5334)
			(layers "B.Cu" "B.Mask" "B.Paste")
			(net "GND")
		)
		(zone
			(layer "B.Cu")
			(hatch none 0.5)
			(connect_pads
				(clearance 0)
			)
			(min_thickness 0.25)
			(keepout
				(tracks not_allowed)
				(vias allowed)
				(pads allowed)
				(copperpour not_allowed)
				(footprints allowed)
			)
			(placement
				(enabled no)
				(sheetname "")
			)
			(fill
				(thermal_gap 0.5)
				(thermal_bridge_width 0.5)
				(island_removal_mode 0)
			)
			(polygon
				(pts
					(xy 47.1043 35.7378) (xy 47.1043 35.687) (xy 47.0535 35.687) (xy 47.0535 35.7378)
				)
			)
		)
	)
	(footprint ""
		(layer "B.Cu")
		(at 26.543 32.639)
		(property "Reference" "R179"
			(at -0.78867 3.048 270)
			(unlocked yes)
			(layer "B.SilkS")
			(effects
				(font
					(size 0.7874 0.5842)
					(thickness 0.127)
				)
				(justify left mirror)
			)
		)
		(property "Value" "0"
			(at 0.148158 1.3462 270)
			(unlocked yes)
			(layer "B.Fab")
			(hide yes)
			(effects
				(font
					(size 1.27 0.9652)
					(thickness 0.000001)
				)
				(justify left mirror)
			)
		)
		(property "Device Type" "REST1111"
			(at 0.148158 1.3462 270)
			(unlocked yes)
			(layer "B.Fab")
			(hide yes)
			(effects
				(font
					(size 1.27 0.9652)
					(thickness 0.000001)
				)
				(justify left mirror)
			)
		)
		(duplicate_pad_numbers_are_jumpers no)
		(fp_poly
			(pts
				(xy -0.635 1.0668) (xy -0.635 -1.0668) (xy 0.635 -1.0668) (xy 0.635 1.0668)
			)
			(stroke
				(width 0)
				(type default)
			)
			(fill no)
			(layer "B.CrtYd")
		)
		(fp_line
			(start -0.254 -0.508)
			(end -0.254 0.508)
			(stroke
				(width 0.0254)
				(type default)
			)
			(layer "B.Fab")
		)
		(fp_line
			(start -0.254 0.508)
			(end 0.254 0.508)
			(stroke
				(width 0.0254)
				(type default)
			)
			(layer "B.Fab")
		)
		(fp_line
			(start 0.254 -0.508)
			(end -0.254 -0.508)
			(stroke
				(width 0.0254)
				(type default)
			)
			(layer "B.Fab")
		)
		(fp_line
			(start 0.254 0.508)
			(end 0.254 -0.508)
			(stroke
				(width 0.0254)
				(type default)
			)
			(layer "B.Fab")
		)
		(pad "1" smd rect
			(at 0 -0.4191 180)
			(size 0.508 0.5334)
			(layers "B.Cu" "B.Mask" "B.Paste")
			(net "NFP_CORE_VID0")
		)
		(pad "2" smd rect
			(at 0 0.4191 180)
			(size 0.508 0.5334)
			(layers "B.Cu" "B.Mask" "B.Paste")
			(net "_NFP_CORE_VID0")
		)
		(zone
			(layer "B.Cu")
			(hatch none 0.5)
			(connect_pads
				(clearance 0)
			)
			(min_thickness 0.25)
			(keepout
				(tracks not_allowed)
				(vias allowed)
				(pads allowed)
				(copperpour not_allowed)
				(footprints allowed)
			)
			(placement
				(enabled no)
				(sheetname "")
			)
			(fill
				(thermal_gap 0.5)
				(thermal_bridge_width 0.5)
				(island_removal_mode 0)
			)
			(polygon
				(pts
					(xy 26.5176 32.6136) (xy 26.5176 32.6644) (xy 26.5684 32.6644) (xy 26.5684 32.6136)
				)
			)
		)
	)
	(footprint ""
		(layer "B.Cu")
		(at 48.237013 29.541978)
		(property "Reference" "C200"
			(at -0.003683 -2.998978 270)
			(unlocked yes)
			(layer "B.SilkS")
			(effects
				(font
					(size 0.7874 0.5842)
					(thickness 0.127)
				)
				(justify mirror)
			)
		)
		(property "Value" ""
			(at 0 0 0)
			(layer "B.Fab")
			(effects
				(font
					(size 1.27 1.27)
				)
				(justify mirror)
			)
		)
		(duplicate_pad_numbers_are_jumpers no)
		(fp_circle
			(center 0 0)
			(end 0.104648 0)
			(stroke
				(width 0.1016)
				(type default)
			)
			(fill no)
			(layer "B.SilkS")
		)
		(fp_poly
			(pts
				(xy 0.381 -0.889) (xy 0.381 0.889) (xy -0.381 0.889) (xy -0.381 -0.889)
			)
			(stroke
				(width 0)
				(type default)
			)
			(fill no)
			(layer "B.CrtYd")
		)
		(fp_line
			(start -0.508 -1.016)
			(end -0.508 1.016)
			(stroke
				(width 0.0254)
				(type default)
			)
			(layer "B.Fab")
		)
		(fp_line
			(start -0.508 1.016)
			(end 0.508 1.016)
			(stroke
				(width 0.0254)
				(type default)
			)
			(layer "B.Fab")
		)
		(fp_line
			(start 0.254 -1.016)
			(end -0.508 -1.016)
			(stroke
				(width 0.0254)
				(type default)
			)
			(layer "B.Fab")
		)
		(fp_line
			(start 0.508 -1.016)
			(end 0.254 -1.016)
			(stroke
				(width 0.0254)
				(type default)
			)
			(layer "B.Fab")
		)
		(fp_line
			(start 0.508 1.016)
			(end 0.508 -1.016)
			(stroke
				(width 0.0254)
				(type default)
			)
			(layer "B.Fab")
		)
		(pad "1" smd custom
			(at 0 -0.500126 180)
			(size 0.127 0.127)
			(layers "B.Cu" "B.Mask" "B.Paste")
			(net "VDD_CORE")
			(options
				(clearance outline)
				(anchor circle)
			)
			(primitives
				(gr_poly
					(pts
						(xy -0.1778 0.254) (xy 0.1778 0.254) (xy 0.254 0.1778) (xy 0.254 -0.1778) (xy 0.1778 -0.254) (xy -0.1778 -0.254)
						(xy -0.254 -0.1778) (xy -0.254 0.1778)
					)
					(width 0)
					(fill yes)
				)
			)
		)
		(pad "2" smd custom
			(at 0 0.500126 180)
			(size 0.127 0.127)
			(layers "B.Cu" "B.Mask" "B.Paste")
			(net "GND")
			(options
				(clearance outline)
				(anchor circle)
			)
			(primitives
				(gr_poly
					(pts
						(xy -0.1778 0.254) (xy 0.1778 0.254) (xy 0.254 0.1778) (xy 0.254 -0.1778) (xy 0.1778 -0.254) (xy -0.1778 -0.254)
						(xy -0.254 -0.1778) (xy -0.254 0.1778)
					)
					(width 0)
					(fill yes)
				)
			)
		)
	)
	(footprint ""
		(layer "B.Cu")
		(at 39.237031 14.542008)
		(property "Reference" "R45"
			(at 0.005969 -1.434338 0)
			(unlocked yes)
			(layer "B.SilkS")
			(effects
				(font
					(size 0.7874 0.5842)
					(thickness 0.127)
				)
				(justify mirror)
			)
		)
		(property "Value" ""
			(at 0 0 0)
			(layer "B.Fab")
			(effects
				(font
					(size 1.27 1.27)
				)
				(justify mirror)
			)
		)
		(duplicate_pad_numbers_are_jumpers no)
		(fp_circle
			(center 0 0)
			(end 0.104648 0)
			(stroke
				(width 0.1016)
				(type default)
			)
			(fill no)
			(layer "B.SilkS")
		)
		(fp_poly
			(pts
				(xy 0.381 -0.889) (xy 0.381 0.889) (xy -0.381 0.889) (xy -0.381 -0.889)
			)
			(stroke
				(width 0)
				(type default)
			)
			(fill no)
			(layer "B.CrtYd")
		)
		(fp_line
			(start -0.508 -1.016)
			(end -0.508 1.016)
			(stroke
				(width 0.0254)
				(type default)
			)
			(layer "B.Fab")
		)
		(fp_line
			(start -0.508 1.016)
			(end 0.508 1.016)
			(stroke
				(width 0.0254)
				(type default)
			)
			(layer "B.Fab")
		)
		(fp_line
			(start 0.254 -1.016)
			(end -0.508 -1.016)
			(stroke
				(width 0.0254)
				(type default)
			)
			(layer "B.Fab")
		)
		(fp_line
			(start 0.508 -1.016)
			(end 0.254 -1.016)
			(stroke
				(width 0.0254)
				(type default)
			)
			(layer "B.Fab")
		)
		(fp_line
			(start 0.508 1.016)
			(end 0.508 -1.016)
			(stroke
				(width 0.0254)
				(type default)
			)
			(layer "B.Fab")
		)
		(pad "1" smd custom
			(at 0 -0.500126 180)
			(size 0.127 0.127)
			(layers "B.Cu" "B.Mask" "B.Paste")
			(net "PGRM_JTAG_TCK")
			(options
				(clearance outline)
				(anchor circle)
			)
			(primitives
				(gr_poly
					(pts
						(xy -0.1778 0.254) (xy 0.1778 0.254) (xy 0.254 0.1778) (xy 0.254 -0.1778) (xy 0.1778 -0.254) (xy -0.1778 -0.254)
						(xy -0.254 -0.1778) (xy -0.254 0.1778)
					)
					(width 0)
					(fill yes)
				)
			)
		)
		(pad "2" smd custom
			(at 0 0.500126 180)
			(size 0.127 0.127)
			(layers "B.Cu" "B.Mask" "B.Paste")
			(net "GND")
			(options
				(clearance outline)
				(anchor circle)
			)
			(primitives
				(gr_poly
					(pts
						(xy -0.1778 0.254) (xy 0.1778 0.254) (xy 0.254 0.1778) (xy 0.254 -0.1778) (xy 0.1778 -0.254) (xy -0.1778 -0.254)
						(xy -0.254 -0.1778) (xy -0.254 0.1778)
					)
					(width 0)
					(fill yes)
				)
			)
		)
	)
	(footprint ""
		(layer "B.Cu")
		(at 69.85 35.56 90)
		(property "Reference" "C32"
			(at -1.29667 1.016 0)
			(unlocked yes)
			(layer "B.SilkS")
			(effects
				(font
					(size 0.7874 0.5842)
					(thickness 0.127)
				)
				(justify left mirror)
			)
		)
		(property "Value" "0.22UF"
			(at 0.148158 1.7526 0)
			(unlocked yes)
			(layer "B.Fab")
			(hide yes)
			(effects
				(font
					(size 1.27 0.9652)
					(thickness 0.000001)
				)
				(justify left mirror)
			)
		)
		(property "Device Type" "CAPC0022"
			(at 0.148158 1.7526 0)
			(unlocked yes)
			(layer "B.Fab")
			(hide yes)
			(effects
				(font
					(size 1.27 0.9652)
					(thickness 0.000001)
				)
				(justify left mirror)
			)
		)
		(duplicate_pad_numbers_are_jumpers no)
		(fp_circle
			(center 0 0)
			(end 0 0.127)
			(stroke
				(width 0.2032)
				(type default)
			)
			(fill no)
			(layer "B.SilkS")
		)
		(fp_poly
			(pts
				(xy -0.7874 -1.6637) (xy 0.7874 -1.6637) (xy 0.7874 1.6637) (xy -0.7874 1.6637)
			)
			(stroke
				(width 0)
				(type default)
			)
			(fill no)
			(layer "B.CrtYd")
		)
		(fp_line
			(start 0.4064 -0.7874)
			(end -0.4064 -0.7874)
			(stroke
				(width 0.0254)
				(type default)
			)
			(layer "B.Fab")
		)
		(fp_line
			(start -0.4064 -0.7874)
			(end -0.4064 0.8128)
			(stroke
				(width 0.0254)
				(type default)
			)
			(layer "B.Fab")
		)
		(fp_line
			(start 0.4064 0.8128)
			(end 0.4064 -0.7874)
			(stroke
				(width 0.0254)
				(type default)
			)
			(layer "B.Fab")
		)
		(fp_line
			(start -0.4064 0.8128)
			(end 0.4064 0.8128)
			(stroke
				(width 0.0254)
				(type default)
			)
			(layer "B.Fab")
		)
		(pad "1" smd rect
			(at 0 -0.8001 270)
			(size 0.8636 0.9652)
			(layers "B.Cu" "B.Mask" "B.Paste")
			(net "10N2229")
		)
		(pad "2" smd rect
			(at 0 0.8001 270)
			(size 0.8636 0.9652)
			(layers "B.Cu" "B.Mask" "B.Paste")
			(net "10N2228")
		)
		(zone
			(layer "B.Cu")
			(hatch none 0.5)
			(connect_pads
				(clearance 0)
			)
			(min_thickness 0.25)
			(keepout
				(tracks not_allowed)
				(vias allowed)
				(pads allowed)
				(copperpour not_allowed)
				(footprints allowed)
			)
			(placement
				(enabled no)
				(sheetname "")
			)
			(fill
				(thermal_gap 0.5)
				(thermal_bridge_width 0.5)
				(island_removal_mode 0)
			)
			(polygon
				(pts
					(xy 69.596 35.4965) (xy 69.596 35.6235) (xy 70.104 35.6235) (xy 70.104 35.4965)
				)
			)
		)
	)
)
